(kicad_pcb
	(version 20260206)
	(generator "pcbnew")
	(generator_version "10.0")
	(general
		(thickness 1.6)
		(legacy_teardrops no)
	)
	(paper "A4")
	(title_block
		(title "Bryce Canyon_SCC_16316-1_OCP.brd")
		(comment 1 "Bryce Canyon / footprints 298-304 of 1561")
	)
	(layers
		(0 "F.Cu" signal "TOP")
		(4 "In1.Cu" signal "L2GND")
		(6 "In2.Cu" signal "L3")
		(8 "In3.Cu" signal "L4VCC")
		(10 "In4.Cu" signal "L5VCC")
		(12 "In5.Cu" signal "L6")
		(14 "In6.Cu" signal "L7GND")
		(2 "B.Cu" signal "BOTTOM")
		(9 "F.Adhes" user "F.Adhesive")
		(11 "B.Adhes" user "B.Adhesive")
		(13 "F.Paste" user "Package Geometry/Pastemask Top")
		(15 "B.Paste" user "Package Geometry/Pastemask Bottom")
		(5 "F.SilkS" user "Ref Des/Silkscreen Top")
		(7 "B.SilkS" user "Ref Des/Silkscreen Bottom")
		(1 "F.Mask" user "Board Geometry/Soldermask Top")
		(3 "B.Mask" user "Board Geometry/Soldermask Bottom")
		(17 "Dwgs.User" user "User.Drawings")
		(19 "Cmts.User" user "User.Comments")
		(21 "Eco1.User" user "User.Eco1")
		(23 "Eco2.User" user "User.Eco2")
		(25 "Edge.Cuts" user "Board Geometry/Outline")
		(27 "Margin" user)
		(31 "F.CrtYd" user "Package Geometry/Place Bound Top")
		(29 "B.CrtYd" user "Package Geometry/Place Bound Bottom")
		(35 "F.Fab" user "Ref Des/Assembly Top")
		(33 "B.Fab" user "Ref Des/Assembly Bottom")
	)
	(footprint ""
		(layer "F.Cu")
		(at 71.9074 -107.0356)
		(property "Reference" "R512"
			(at 0 0 0)
			(layer "F.SilkS")
			(hide yes)
			(effects
				(font
					(size 1.27 1.27)
				)
			)
		)
		(property "Value" "10R3F-GP"
			(at -0.0254 -2.5146 0)
			(unlocked yes)
			(layer "F.Fab")
			(hide yes)
			(effects
				(font
					(size 1.016 1.016)
					(thickness 0.1524)
				)
			)
		)
		(property "Device Type" "R603H22"
			(at -0.0254 -4.0386 0)
			(unlocked yes)
			(layer "F.Fab")
			(hide yes)
			(effects
				(font
					(size 1.016 1.016)
					(thickness 0.1524)
				)
			)
		)
		(duplicate_pad_numbers_are_jumpers no)
		(fp_line
			(start -0.4826 0)
			(end -0.2032 0)
			(stroke
				(width 0.2032)
				(type default)
			)
			(layer "F.SilkS")
		)
		(fp_line
			(start 0.2032 0)
			(end 0.4826 0)
			(stroke
				(width 0.2032)
				(type default)
			)
			(layer "F.SilkS")
		)
		(fp_rect
			(start -0.5842 1.3335)
			(end 0.5842 -1.3335)
			(stroke
				(width 0)
				(type default)
			)
			(fill no)
			(layer "F.CrtYd")
		)
		(fp_rect
			(start -0.5842 1.3335)
			(end 0.5842 -1.3335)
			(stroke
				(width 0)
				(type default)
			)
			(fill no)
			(layer "F.Fab")
		)
		(pad "1" smd custom
			(at 0 -0.762)
			(size 0.2159 0.2159)
			(layers "F.Cu" "F.Mask" "F.Paste")
			(net "P3V3_OUT")
			(options
				(clearance outline)
				(anchor circle)
			)
			(primitives
				(gr_poly
					(pts
						(arc
							(start -0.3302 -0.4318)
							(mid -0.402042 -0.402042)
							(end -0.4318 -0.3302)
						)
						(arc
							(start -0.4318 0.3302)
							(mid -0.402042 0.402042)
							(end -0.3302 0.4318)
						)
						(arc
							(start 0.3302 0.4318)
							(mid 0.402042 0.402042)
							(end 0.4318 0.3302)
						)
						(arc
							(start 0.4318 -0.3302)
							(mid 0.402042 -0.402042)
							(end 0.3302 -0.4318)
						)
					)
					(width 0)
					(fill yes)
				)
			)
		)
		(pad "2" smd custom
			(at 0 0.762)
			(size 0.2159 0.2159)
			(layers "F.Cu" "F.Mask" "F.Paste")
			(net "P3V3_VFB_R")
			(options
				(clearance outline)
				(anchor circle)
			)
			(primitives
				(gr_poly
					(pts
						(arc
							(start -0.3302 -0.4318)
							(mid -0.402042 -0.402042)
							(end -0.4318 -0.3302)
						)
						(arc
							(start -0.4318 0.3302)
							(mid -0.402042 0.402042)
							(end -0.3302 0.4318)
						)
						(arc
							(start 0.3302 0.4318)
							(mid 0.402042 0.402042)
							(end 0.4318 0.3302)
						)
						(arc
							(start 0.4318 -0.3302)
							(mid 0.402042 -0.402042)
							(end 0.3302 -0.4318)
						)
					)
					(width 0)
					(fill yes)
				)
			)
		)
	)
	(footprint ""
		(layer "F.Cu")
		(at 8.5598 -57.2008)
		(property "Reference" "R688"
			(at 0 0 0)
			(layer "F.SilkS")
			(hide yes)
			(effects
				(font
					(size 1.27 1.27)
				)
			)
		)
		(property "Value" "10KR2F-2-GP"
			(at 0.064008 -3.993896 0)
			(unlocked yes)
			(layer "F.Fab")
			(hide yes)
			(effects
				(font
					(size 1.016 1.016)
					(thickness 0.1524)
				)
			)
		)
		(property "Device Type" "R402H16"
			(at 0.064008 -5.517896 0)
			(unlocked yes)
			(layer "F.Fab")
			(hide yes)
			(effects
				(font
					(size 1.016 1.016)
					(thickness 0.1524)
				)
			)
		)
		(duplicate_pad_numbers_are_jumpers no)
		(fp_line
			(start -0.508 -0.9398)
			(end -0.508 0.9398)
			(stroke
				(width 0.1524)
				(type default)
			)
			(layer "F.SilkS")
		)
		(fp_line
			(start 0.508 -0.9398)
			(end -0.508 -0.9398)
			(stroke
				(width 0.1524)
				(type default)
			)
			(layer "F.SilkS")
		)
		(fp_rect
			(start -0.508 0.9398)
			(end 0.508 -0.9398)
			(stroke
				(width 0)
				(type default)
			)
			(fill no)
			(layer "F.CrtYd")
		)
		(fp_rect
			(start -0.508 0.9398)
			(end 0.508 -0.9398)
			(stroke
				(width 0)
				(type default)
			)
			(fill no)
			(layer "F.Fab")
		)
		(pad "1" smd custom
			(at 0 -0.4445)
			(size 0.1397 0.1397)
			(layers "F.Cu" "F.Mask" "F.Paste")
			(net "GND")
			(options
				(clearance outline)
				(anchor circle)
			)
			(primitives
				(gr_poly
					(pts
						(arc
							(start -0.1778 -0.2794)
							(mid -0.249642 -0.249642)
							(end -0.2794 -0.1778)
						)
						(arc
							(start -0.2794 0.1778)
							(mid -0.249642 0.249642)
							(end -0.1778 0.2794)
						)
						(arc
							(start 0.1778 0.2794)
							(mid 0.249642 0.249642)
							(end 0.2794 0.1778)
						)
						(arc
							(start 0.2794 -0.1778)
							(mid 0.249642 -0.249642)
							(end 0.1778 -0.2794)
						)
					)
					(width 0)
					(fill yes)
				)
			)
		)
		(pad "2" smd custom
			(at 0 0.4445)
			(size 0.1397 0.1397)
			(layers "F.Cu" "F.Mask" "F.Paste")
			(net "MB0_RETRY_R")
			(options
				(clearance outline)
				(anchor circle)
			)
			(primitives
				(gr_poly
					(pts
						(arc
							(start -0.1778 -0.2794)
							(mid -0.249642 -0.249642)
							(end -0.2794 -0.1778)
						)
						(arc
							(start -0.2794 0.1778)
							(mid -0.249642 0.249642)
							(end -0.1778 0.2794)
						)
						(arc
							(start 0.1778 0.2794)
							(mid 0.249642 0.249642)
							(end 0.2794 0.1778)
						)
						(arc
							(start 0.2794 -0.1778)
							(mid 0.249642 -0.249642)
							(end 0.1778 -0.2794)
						)
					)
					(width 0)
					(fill yes)
				)
			)
		)
	)
	(footprint ""
		(layer "F.Cu")
		(at 70.485 -39.751 90)
		(property "Reference" "L14"
			(at 0 0 90)
			(layer "F.SilkS")
			(hide yes)
			(effects
				(font
					(size 1.27 1.27)
				)
			)
		)
		(property "Value" "MPZ2012S300AT-GP"
			(at 0 -4.2418 90)
			(unlocked yes)
			(layer "F.Fab")
			(hide yes)
			(effects
				(font
					(size 1.016 1.016)
					(thickness 0.1524)
				)
			)
		)
		(property "Device Type" "L805H42"
			(at 0 -5.7912 90)
			(unlocked yes)
			(layer "F.Fab")
			(hide yes)
			(effects
				(font
					(size 1.016 1.016)
					(thickness 0.1524)
				)
			)
		)
		(duplicate_pad_numbers_are_jumpers no)
		(fp_line
			(start 0.889 -1.7018)
			(end 0.889 1.7018)
			(stroke
				(width 0.1524)
				(type default)
			)
			(layer "F.SilkS")
		)
		(fp_line
			(start -0.889 -1.7018)
			(end 0.889 -1.7018)
			(stroke
				(width 0.1524)
				(type default)
			)
			(layer "F.SilkS")
		)
		(fp_line
			(start 0.889 1.7018)
			(end -0.889 1.7018)
			(stroke
				(width 0.1524)
				(type default)
			)
			(layer "F.SilkS")
		)
		(fp_line
			(start -0.889 1.7018)
			(end -0.889 -1.7018)
			(stroke
				(width 0.1524)
				(type default)
			)
			(layer "F.SilkS")
		)
		(fp_rect
			(start -0.9652 1.778)
			(end 0.9652 -1.778)
			(stroke
				(width 0)
				(type default)
			)
			(fill no)
			(layer "F.CrtYd")
		)
		(fp_rect
			(start -0.9652 1.778)
			(end 0.9652 -1.778)
			(stroke
				(width 0)
				(type default)
			)
			(fill no)
			(layer "F.Fab")
		)
		(pad "1" smd rect
			(at 0 -0.9652 90)
			(size 1.397 1.143)
			(layers "F.Cu" "F.Mask" "F.Paste")
			(net "P0V9")
		)
		(pad "2" smd rect
			(at 0 0.9652 90)
			(size 1.397 1.143)
			(layers "F.Cu" "F.Mask" "F.Paste")
			(net "GB_VDDA")
		)
	)
	(footprint ""
		(layer "F.Cu")
		(at 173.4058 -59.817 180)
		(property "Reference" "R275"
			(at 0 0 180)
			(layer "F.SilkS")
			(hide yes)
			(effects
				(font
					(size 1.27 1.27)
				)
			)
		)
		(property "Value" "4K7R2F-GP"
			(at 0.064008 -3.993896 180)
			(unlocked yes)
			(layer "F.Fab")
			(hide yes)
			(effects
				(font
					(size 1.016 1.016)
					(thickness 0.1524)
				)
			)
		)
		(property "Device Type" "R402H16"
			(at 0.064008 -5.517896 180)
			(unlocked yes)
			(layer "F.Fab")
			(hide yes)
			(effects
				(font
					(size 1.016 1.016)
					(thickness 0.1524)
				)
			)
		)
		(duplicate_pad_numbers_are_jumpers no)
		(fp_line
			(start 0.508 -0.9398)
			(end -0.508 -0.9398)
			(stroke
				(width 0.1524)
				(type default)
			)
			(layer "F.SilkS")
		)
		(fp_line
			(start -0.508 -0.9398)
			(end -0.508 0.9398)
			(stroke
				(width 0.1524)
				(type default)
			)
			(layer "F.SilkS")
		)
		(fp_rect
			(start -0.508 0.9398)
			(end 0.508 -0.9398)
			(stroke
				(width 0)
				(type default)
			)
			(fill no)
			(layer "F.CrtYd")
		)
		(fp_rect
			(start -0.508 0.9398)
			(end 0.508 -0.9398)
			(stroke
				(width 0)
				(type default)
			)
			(fill no)
			(layer "F.Fab")
		)
		(pad "1" smd custom
			(at 0 -0.4445 180)
			(size 0.1397 0.1397)
			(layers "F.Cu" "F.Mask" "F.Paste")
			(net "IOC_TRST_N")
			(options
				(clearance outline)
				(anchor circle)
			)
			(primitives
				(gr_poly
					(pts
						(arc
							(start -0.1778 -0.2794)
							(mid -0.249642 -0.249642)
							(end -0.2794 -0.1778)
						)
						(arc
							(start -0.2794 0.1778)
							(mid -0.249642 0.249642)
							(end -0.1778 0.2794)
						)
						(arc
							(start 0.1778 0.2794)
							(mid 0.249642 0.249642)
							(end 0.2794 0.1778)
						)
						(arc
							(start 0.2794 -0.1778)
							(mid 0.249642 -0.249642)
							(end 0.1778 -0.2794)
						)
					)
					(width 0)
					(fill yes)
				)
			)
		)
		(pad "2" smd custom
			(at 0 0.4445 180)
			(size 0.1397 0.1397)
			(layers "F.Cu" "F.Mask" "F.Paste")
			(net "GND")
			(options
				(clearance outline)
				(anchor circle)
			)
			(primitives
				(gr_poly
					(pts
						(arc
							(start -0.1778 -0.2794)
							(mid -0.249642 -0.249642)
							(end -0.2794 -0.1778)
						)
						(arc
							(start -0.2794 0.1778)
							(mid -0.249642 0.249642)
							(end -0.1778 0.2794)
						)
						(arc
							(start 0.1778 0.2794)
							(mid 0.249642 0.249642)
							(end 0.2794 0.1778)
						)
						(arc
							(start 0.2794 -0.1778)
							(mid 0.249642 -0.249642)
							(end 0.1778 -0.2794)
						)
					)
					(width 0)
					(fill yes)
				)
			)
		)
	)
	(footprint ""
		(layer "F.Cu")
		(at 157.2006 -81.5594 180)
		(property "Reference" "R322"
			(at 0 0 180)
			(layer "F.SilkS")
			(hide yes)
			(effects
				(font
					(size 1.27 1.27)
				)
			)
		)
		(property "Value" "1KR2F-3-GP"
			(at 0.064008 -3.993896 180)
			(unlocked yes)
			(layer "F.Fab")
			(hide yes)
			(effects
				(font
					(size 1.016 1.016)
					(thickness 0.1524)
				)
			)
		)
		(property "Device Type" "R402H16"
			(at 0.064008 -5.517896 180)
			(unlocked yes)
			(layer "F.Fab")
			(hide yes)
			(effects
				(font
					(size 1.016 1.016)
					(thickness 0.1524)
				)
			)
		)
		(duplicate_pad_numbers_are_jumpers no)
		(fp_line
			(start 0.508 -0.9398)
			(end -0.508 -0.9398)
			(stroke
				(width 0.1524)
				(type default)
			)
			(layer "F.SilkS")
		)
		(fp_line
			(start -0.508 -0.9398)
			(end -0.508 0.9398)
			(stroke
				(width 0.1524)
				(type default)
			)
			(layer "F.SilkS")
		)
		(fp_rect
			(start -0.508 0.9398)
			(end 0.508 -0.9398)
			(stroke
				(width 0)
				(type default)
			)
			(fill no)
			(layer "F.CrtYd")
		)
		(fp_rect
			(start -0.508 0.9398)
			(end 0.508 -0.9398)
			(stroke
				(width 0)
				(type default)
			)
			(fill no)
			(layer "F.Fab")
		)
		(pad "1" smd custom
			(at 0 -0.4445 180)
			(size 0.1397 0.1397)
			(layers "F.Cu" "F.Mask" "F.Paste")
			(net "P1V5_E")
			(options
				(clearance outline)
				(anchor circle)
			)
			(primitives
				(gr_poly
					(pts
						(arc
							(start -0.1778 -0.2794)
							(mid -0.249642 -0.249642)
							(end -0.2794 -0.1778)
						)
						(arc
							(start -0.2794 0.1778)
							(mid -0.249642 0.249642)
							(end -0.1778 0.2794)
						)
						(arc
							(start 0.1778 0.2794)
							(mid 0.249642 0.249642)
							(end 0.2794 0.1778)
						)
						(arc
							(start 0.2794 -0.1778)
							(mid 0.249642 -0.249642)
							(end 0.1778 -0.2794)
						)
					)
					(width 0)
					(fill yes)
				)
			)
		)
		(pad "2" smd custom
			(at 0 0.4445 180)
			(size 0.1397 0.1397)
			(layers "F.Cu" "F.Mask" "F.Paste")
			(net "P1V5_E_SENSE")
			(options
				(clearance outline)
				(anchor circle)
			)
			(primitives
				(gr_poly
					(pts
						(arc
							(start -0.1778 -0.2794)
							(mid -0.249642 -0.249642)
							(end -0.2794 -0.1778)
						)
						(arc
							(start -0.2794 0.1778)
							(mid -0.249642 0.249642)
							(end -0.1778 0.2794)
						)
						(arc
							(start 0.1778 0.2794)
							(mid 0.249642 0.249642)
							(end 0.2794 0.1778)
						)
						(arc
							(start 0.2794 -0.1778)
							(mid 0.249642 -0.249642)
							(end 0.1778 -0.2794)
						)
					)
					(width 0)
					(fill yes)
				)
			)
		)
	)
	(footprint ""
		(layer "F.Cu")
		(at 186.820048 -100.00361 180)
		(property "Reference" "L27"
			(at 0 0 180)
			(layer "F.SilkS")
			(hide yes)
			(effects
				(font
					(size 1.27 1.27)
				)
			)
		)
		(property "Value" "28F0181-1SR-10-GP"
			(at -4.064 -3.5052 180)
			(unlocked yes)
			(layer "F.Fab")
			(hide yes)
			(effects
				(font
					(size 1.016 1.016)
					(thickness 0.1524)
				)
			)
		)
		(property "Device Type" "L9546-152127H121"
			(at -4.064 -5.0292 180)
			(unlocked yes)
			(layer "F.Fab")
			(hide yes)
			(effects
				(font
					(size 1.016 1.016)
					(thickness 0.1524)
				)
			)
		)
		(duplicate_pad_numbers_are_jumpers no)
		(fp_line
			(start 2.54 5.6642)
			(end 2.54 -5.6642)
			(stroke
				(width 0.1524)
				(type default)
			)
			(layer "F.SilkS")
		)
		(fp_line
			(start 2.54 -5.6642)
			(end -2.54 -5.6642)
			(stroke
				(width 0.1524)
				(type default)
			)
			(layer "F.SilkS")
		)
		(fp_line
			(start -2.54 5.6642)
			(end 2.54 5.6642)
			(stroke
				(width 0.1524)
				(type default)
			)
			(layer "F.SilkS")
		)
		(fp_line
			(start -2.54 -5.6642)
			(end -2.54 5.6642)
			(stroke
				(width 0.1524)
				(type default)
			)
			(layer "F.SilkS")
		)
		(fp_rect
			(start -2.286 4.7625)
			(end 2.286 -4.7625)
			(stroke
				(width 0)
				(type default)
			)
			(fill no)
			(layer "F.CrtYd")
		)
		(fp_poly
			(pts
				(xy -2.794 5.7404) (xy -2.794 -5.7404) (xy 2.794 -5.7404) (xy 2.794 5.7404) (xy 0.00254 5.7404)
				(xy 0.00254 4.7625) (xy 2.286 4.7625) (xy 2.286 -4.7625) (xy -2.286 -4.7625) (xy -2.286 4.7625)
				(xy -0.00254 4.7625) (xy -0.00254 5.7404)
			)
			(stroke
				(width 0)
				(type default)
			)
			(fill no)
			(layer "F.CrtYd")
		)
		(fp_rect
			(start -2.794 5.7404)
			(end 2.794 -5.7404)
			(stroke
				(width 0)
				(type default)
			)
			(fill no)
			(layer "F.Fab")
		)
		(pad "1" smd rect
			(at 0 -4.197604 180)
			(size 1.524 2.413)
			(layers "F.Cu" "F.Mask" "F.Paste")
			(net "P0V975")
		)
		(pad "2" smd rect
			(at 0 4.197604 180)
			(size 1.524 2.413)
			(layers "F.Cu" "F.Mask" "F.Paste")
			(net "SAS0_AVDD")
		)
	)
	(footprint ""
		(layer "F.Cu")
		(at 56.896 -115.951 -90)
		(property "Reference" "TC4"
			(at 0 0 270)
			(layer "F.SilkS")
			(hide yes)
			(effects
				(font
					(size 1.27 1.27)
				)
			)
		)
		(property "Value" "ST150U6D3VDM-28-GP"
			(at 0 -9.6012 270)
			(unlocked yes)
			(layer "F.Fab")
			(hide yes)
			(effects
				(font
					(size 1.016 1.016)
					(thickness 0.1524)
				)
			)
		)
		(property "Device Type" "CT7343H83"
			(at 0 -11.1252 270)
			(unlocked yes)
			(layer "F.Fab")
			(hide yes)
			(effects
				(font
					(size 1.016 1.016)
					(thickness 0.1524)
				)
			)
		)
		(duplicate_pad_numbers_are_jumpers no)
		(fp_line
			(start -2.286 4.8768)
			(end -2.286 2.032)
			(stroke
				(width 0.1524)
				(type default)
			)
			(layer "F.SilkS")
		)
		(fp_line
			(start 2.286 4.8768)
			(end -2.286 4.8768)
			(stroke
				(width 0.1524)
				(type default)
			)
			(layer "F.SilkS")
		)
		(fp_line
			(start 2.286 2.032)
			(end 2.286 4.8768)
			(stroke
				(width 0.1524)
				(type default)
			)
			(layer "F.SilkS")
		)
		(fp_line
			(start 2.286 -2.032)
			(end 2.286 -4.8768)
			(stroke
				(width 0.1524)
				(type default)
			)
			(layer "F.SilkS")
		)
		(fp_line
			(start 2.1082 -4.699)
			(end -2.1082 -4.699)
			(stroke
				(width 0.508)
				(type default)
			)
			(layer "F.SilkS")
		)
		(fp_line
			(start -2.286 -4.8768)
			(end -2.286 -2.032)
			(stroke
				(width 0.1524)
				(type default)
			)
			(layer "F.SilkS")
		)
		(fp_line
			(start 2.286 -4.8768)
			(end -2.286 -4.8768)
			(stroke
				(width 0.1524)
				(type default)
			)
			(layer "F.SilkS")
		)
		(fp_rect
			(start -2.1463 3.6449)
			(end 2.1463 -3.6449)
			(stroke
				(width 0)
				(type default)
			)
			(fill no)
			(layer "F.CrtYd")
		)
		(fp_poly
			(pts
				(xy -2.54 4.953) (xy -2.54 4.2926) (xy -3.81 4.2926) (xy -3.81 -4.2926) (xy -2.54 -4.2926) (xy -2.54 -4.953)
				(xy 2.54 -4.953) (xy 2.54 -4.2926) (xy 3.81 -4.2926) (xy 3.81 -1.6256) (xy 2.1463 -1.6256) (xy 2.1463 -3.6449)
				(xy -2.1463 -3.6449) (xy -2.1463 3.6449) (xy 2.1463 3.6449) (xy 2.1463 -1.6129) (xy 3.81 -1.6129)
				(xy 3.81 4.2926) (xy 2.54 4.2926) (xy 2.54 4.953)
			)
			(stroke
				(width 0)
				(type default)
			)
			(fill no)
			(layer "F.CrtYd")
		)
		(fp_rect
			(start -2.54 4.953)
			(end 2.54 -4.953)
			(stroke
				(width 0)
				(type default)
			)
			(fill no)
			(layer "F.Fab")
		)
		(fp_rect
			(start -3.81 4.2926)
			(end -2.54 -4.2926)
			(stroke
				(width 0)
				(type default)
			)
			(fill no)
			(layer "F.Fab")
		)
		(fp_rect
			(start 2.54 4.2926)
			(end 3.81 -4.2926)
			(stroke
				(width 0)
				(type default)
			)
			(fill no)
			(layer "F.Fab")
		)
		(pad "1" smd rect
			(at 0 -3.1496 270)
			(size 2.413 2.286)
			(layers "F.Cu" "F.Mask" "F.Paste")
			(net "P3V3_OUT")
		)
		(pad "2" smd rect
			(at 0 3.1496 270)
			(size 2.413 2.286)
			(layers "F.Cu" "F.Mask" "F.Paste")
			(net "GND")
		)
		(zone
			(layer "F.Cu")
			(hatch none 0.5)
			(connect_pads
				(clearance 0)
			)
			(min_thickness 0.25)
			(keepout
				(tracks allowed)
				(vias not_allowed)
				(pads allowed)
				(copperpour not_allowed)
				(footprints allowed)
			)
			(placement
				(enabled no)
				(sheetname "")
			)
			(fill
				(thermal_gap 0.5)
				(thermal_bridge_width 0.5)
				(island_removal_mode 0)
			)
			(polygon
				(pts
					(xy 52.2986 -117.4623) (xy 52.2986 -114.4397) (xy 55.1942 -114.4397) (xy 55.5244 -114.4397) (xy 55.5244 -117.4623)
					(xy 55.1942 -117.4623)
				)
			)
		)
		(zone
			(layer "F.Cu")
			(hatch none 0.5)
			(connect_pads
				(clearance 0)
			)
			(min_thickness 0.25)
			(keepout
				(tracks allowed)
				(vias not_allowed)
				(pads allowed)
				(copperpour not_allowed)
				(footprints allowed)
			)
			(placement
				(enabled no)
				(sheetname "")
			)
			(fill
				(thermal_gap 0.5)
				(thermal_bridge_width 0.5)
				(island_removal_mode 0)
			)
			(polygon
				(pts
					(xy 58.5851 -114.4397) (xy 61.4934 -114.4397) (xy 61.4934 -117.4623) (xy 58.5978 -117.4623) (xy 58.2676 -117.4623)
					(xy 58.2676 -114.4397)
				)
			)
		)
	)
)
